FILE_TYPE = CONNECTIVITY;
{Allegro Design Entry HDL 16.6-p007 (v16-6-112F) 10/10/2012}
"PAGE_NUMBER" = 161;
0"NC";
1"GND\g";
2"P3V3_STBY\g";
3"P12V_FAN\g";
4"P12V_FAN\g";
5"GND\g";
6"P3V3_STBY\g";
7"GND\g";
8"P3V3_STBY\g";
9"GND\g";
10"GND\g";
11"GND\g";
12"P3V3_STBY\g";
13"GND\g";
14"P3V3_STBY\g";
15"GND\g";
16"GND\g";
17"P3V3_STBY\g";
18"P5V_STBY\g";
19"P3V3_STBY\g";
20"P5V_STBY\g";
21"GND\g";
22"P3V3_STBY\g";
23"GND\g";
24"FAN_PWM_OUT_SYS0_R";
25"FAN_TACH1_CPU1_D1";
26"FAN_TACH0_CPU0_D1";
27"TP_FAN_0";
28"FAN_PWM_OUT_SYS1_R";
29"FAN_TACH3_CPU1_D1";
30"FAN_TACH2_CPU1_D1";
31"TP_FAN_1";
32"FAN_TACH0_CPU0_D2";
33"FAN_TACH3_CPU1_D2";
34"FAN_TACH2_CPU1_D2";
35"FAN_TACH0";
36"FAN_TACH1_CPU1_D2";
37"FAN_TACH1";
38"FAN_TACH2";
39"FAN_TACH3";
40"FAN_PWM_OUT_SYS0_R";
41"FM_ENABLE_FAN_POWER";
42"FAN_PWM_OUT_SYS1_R";
43"FAN_PWM_OUT_SYS1_BUF";
44"FAN_PWM_OUT_SYS0_BUF";
45"FM_CTNR_PS_ON";
46"FM_DISABLE_FAN_N";
47"FAN_PWM_OUT_SYS0";
48"FAN_PWM_OUT_SYS1";
%"CONN6_C74770005"
"1","(-725,3775)","0","mstr_conn","I1";
;
CDS_SEC"1"
VALUE"0.22UF"
TOLERANCE"10%"
PACK_TYPE"PIP"
VOLTAGE"16V"
SEC_TYPE"PIP"
BOM_COST"SM_THERM"
SEC"1"
CDS_LOCATION"J1F2"
ROOM"CPU_FANS"
CDS_LIB"mstr_conn"
LOCATION"J1F2"
PART_NUMBER"C74770-005"
MATERIAL"HDR";
"IO6"
$PN"6"27;
"IO5"
$PN"5"25;
"IO4"
$PN"4"24;
"IO3"
$PN"3"26;
"IO2"
$PN"2"4;
"IO1"
$PN"1"9;
%"RES"
"1","(-5600,1100)","0","mstr_discrete","I102";
;
CDS_SEC"1"
CDS_LIB"mstr_discrete"
BOM_COST"SM_THERM"
SEC_TYPE"0402"
SEC"1"
CDS_LOCATION"R2U44"
ROOM"CPU_FANS"
LOCATION"R2U44"
PART_NUMBER"G21796-271"
VALUE"221"
TOLERANCE"1.0%"
PACK_TYPE"0402"
MATERIAL"CHIP"
WATTAGE"1/16W";
"B"
$PN"2"42;
"A"
$PN"1"43;
%"GND"
"1","(-6200,475)","2","mstr_symbols","I104";
;
HDL_POWER"GND"
ROOM"PLD"
CDS_LIB"mstr_symbols"
SIZE"1B"
VOLTAGE"0.0V"
BODY_TYPE"PLUMBING";
"A\NAC"1;
%"P3V3_STBY"
"1","(-6200,850)","0","mstr_symbols","I105";
;
SIZE"1B"
CDS_LIB"mstr_symbols"
BODY_TYPE"PLUMBING"
VOLTAGE"3.3V"
HDL_POWER"P3V3_STBY";
"G\NAC"2;
%"P12V_FAN"
"1","(-1375,2575)","0","mstr_symbols","I108";
;
CDS_LIB"mstr_symbols"
HDL_POWER"P12V_FAN"
VOLTAGE"12.0V"
BODY_TYPE"PLUMBING";
"G\NAC"3;
%"P12V_FAN"
"1","(-1500,4725)","0","mstr_symbols","I110";
;
CDS_LIB"mstr_symbols"
HDL_POWER"P12V_FAN"
VOLTAGE"12.0V"
BODY_TYPE"PLUMBING";
"G\NAC"4;
%"GND"
"1","(-1200,1850)","5","mstr_symbols","I111";
;
HDL_POWER"GND"
VOLTAGE"0.0V"
CDS_LIB"mstr_symbols"
SIZE"1B"
BODY_TYPE"PLUMBING";
"A\NAC"5;
%"CAP_A"
"1","(-5775,2150)","0","dev_discrete","I113";
;
BOM_COST"SM_THERM"
SEC_TYPE"0402V"
SEC"1"
ROOM"CPUFANS"
CDS_SEC"1"
CDS_LOCATION"C1E22"
CDS_LIB"dev_discrete"
LOCATION"C1E22"
VALUE"0.1UF"
MATERIAL"X7R"
VOLTAGE"16V"
TOLERANCE"10%"
PART_NUMBER"A36096-030"
PACK_TYPE"0402V";
"B"
$PN"2"7;
"A"
$PN"1"6;
%"P3V3_STBY"
"1","(-5775,2350)","0","mstr_symbols","I117";
;
BODY_TYPE"PLUMBING"
VOLTAGE"3.3V"
CDS_LIB"mstr_symbols"
SIZE"1B"
HDL_POWER"P3V3_STBY";
"G\NAC"6;
%"GND"
"1","(-5775,1950)","0","mstr_symbols","I118";
;
HDL_POWER"GND"
BODY_TYPE"PLUMBING"
SIZE"1B"
CDS_LIB"mstr_symbols"
VOLTAGE"0.0V";
"A\NAC"7;
%"P3V3_STBY"
"1","(-5950,3025)","0","mstr_symbols","I119";
;
VOLTAGE"3.3V"
CDS_LIB"mstr_symbols"
SIZE"1B"
BODY_TYPE"PLUMBING"
HDL_POWER"P3V3_STBY";
"G\NAC"8;
%"RES"
"2","(-5950,2800)","0","mstr_discrete","I120";
;
CDS_SEC"1"
BOM_COST"SM_THERM"
SEC_TYPE"0402"
SEC"1"
ROOM"CPU_FANS"
CDS_LOCATION"R1E11"
CDS_LIB"mstr_discrete"
PART_NUMBER"G21796-016"
MATERIAL"EMPTY"
LOCATION"R1E11"
VALUE"10.0K"
TOLERANCE"1%"
PACK_TYPE"0402"
WATTAGE"1/16W";
"A"
$PN"1"8;
"B"
$PN"2"41;
%"TTL1G08"
"1","(-6250,2575)","0","mstr_ttl","I121";
;
CDS_SEC"1"
BOM_COST"SM_THERM"
SEC"1"
SEC_TYPE"SOTLF"
ROOM"CPU_FANS"
CDS_LIB"mstr_ttl"
CDS_LOCATION"U1E2"
POWER_GROUP"VCC=P3V3_STBY;GND=GND;"
PART_NUMBER"D10321-001"
LOCATION"U1E2"
PACK_TYPE"SOTLF"
MATERIAL"IC"
VALUE"NC7SZ08";
"Y <SIZE-1..0>"
$PN"4"41;
"B <SIZE-1..0>"
$PN"2"46;
"A <SIZE-1..0>"
$PN"1"45;
%"GND"
"1","(-1125,3925)","5","mstr_symbols","I122";
;
HDL_POWER"GND"
CDS_LIB"mstr_symbols"
SIZE"1B"
BODY_TYPE"PLUMBING"
VOLTAGE"0.0V";
"A\NAC"9;
%"DIODE"
"1","(-1775,675)","0","mstr_discrete","I123";
;
CDS_SEC"1"
BOM_COST"SM_THERM"
SEC"1"
SEC_TYPE"SM"
CDS_LIB"mstr_discrete"
CDS_LOCATION"CR1B3"
ROOM"CPU_FANS"
PART_NUMBER"H71799-001"
PACK_TYPE"SM"
LOCATION"CR1B3"
VALUE"SDMK0340L"
MATERIAL"IC";
"C"
$PN"1"29;
"A"
$PN"2"33;
%"RES"
"1","(-2625,675)","0","mstr_discrete","I124";
;
CDS_SEC"1"
ROOM"CPU_FANS"
SEC"1"
BOM_COST"SM_THERM"
SEC_TYPE"0402"
CDS_LIB"mstr_discrete"
CDS_LOCATION"R1B23"
PACK_TYPE"0402"
LOCATION"R1B23"
PART_NUMBER"G21796-017"
MATERIAL"CHIP"
TOLERANCE"1%"
WATTAGE"1/16W"
VALUE"100.0";
"B"
$PN"2"33;
"A"
$PN"1"39;
%"RES"
"2","(-2925,825)","2","mstr_discrete","I126";
;
CDS_SEC"1"
SEC_TYPE"0402"
BOM_COST"SM_THERM"
SEC"1"
ROOM"CPU_FANS"
CDS_LIB"mstr_discrete"
CDS_LOCATION"R1B24"
TOLERANCE"1%"
LOCATION"R1B24"
PART_NUMBER"G21796-072"
VALUE"4.75K"
MATERIAL"CHIP"
WATTAGE"1/16W"
PACK_TYPE"0402";
"A"
$PN"1"12;
"B"
$PN"2"39;
%"CAP_A"
"1","(-3175,550)","2","dev_discrete","I128";
;
CDS_LOCATION"C1B17"
SEC"1"
SEC_TYPE"0402V"
CDS_LIB"dev_discrete"
BOM_COST"SM_THERM"
CDS_SEC"1"
ROOM"CPU_FANS"
LOCATION"C1B17"
VOLTAGE"25V"
VALUE"0.01UF"
TOLERANCE"10%"
MATERIAL"X7R"
PART_NUMBER"A36096-045"
PACK_TYPE"0402V";
"B"
$PN"2"10;
"A"
$PN"1"39;
%"GND"
"1","(-3175,375)","0","mstr_symbols","I129";
;
HDL_POWER"GND"
SIZE"1B"
CDS_LIB"mstr_symbols"
BODY_TYPE"PLUMBING"
VOLTAGE"0.0V";
"A\NAC"10;
%"GND"
"1","(-1125,4075)","0","mstr_symbols","I13";
;
HDL_POWER"GND"
CDS_LIB"mstr_symbols"
SIZE"1B"
VOLTAGE"0.0V"
BODY_TYPE"PLUMBING";
"A\NAC"11;
%"P3V3_STBY"
"1","(-2925,1000)","0","mstr_symbols","I130";
;
SIZE"1B"
CDS_LIB"mstr_symbols"
VOLTAGE"3.3V"
BODY_TYPE"PLUMBING"
HDL_POWER"P3V3_STBY";
"G\NAC"12;
%"GND"
"1","(-3300,2400)","0","mstr_symbols","I132";
;
HDL_POWER"GND"
SIZE"1B"
CDS_LIB"mstr_symbols"
BODY_TYPE"PLUMBING"
VOLTAGE"0.0V";
"A\NAC"13;
%"DIODE"
"1","(-1975,2775)","0","mstr_discrete","I133";
;
CDS_SEC"1"
BOM_COST"SM_THERM"
SEC_TYPE"SM"
SEC"1"
CDS_LIB"mstr_discrete"
CDS_LOCATION"CR1F2"
ROOM"CPU_FANS"
PACK_TYPE"SM"
PART_NUMBER"H71799-001"
VALUE"SDMK0340L"
LOCATION"CR1F2"
MATERIAL"IC";
"C"
$PN"1"25;
"A"
$PN"2"36;
%"RES"
"1","(-2850,2775)","0","mstr_discrete","I134";
;
CDS_SEC"1"
BOM_COST"SM_THERM"
ROOM"CPU_FANS"
SEC_TYPE"0402"
SEC"1"
CDS_LOCATION"R9T7"
CDS_LIB"mstr_discrete"
PACK_TYPE"0402"
TOLERANCE"1%"
PART_NUMBER"G21796-017"
LOCATION"R9T7"
MATERIAL"CHIP"
VALUE"100.0"
WATTAGE"1/16W";
"B"
$PN"2"36;
"A"
$PN"1"37;
%"RES"
"2","(-3225,2925)","2","mstr_discrete","I135";
;
CDS_SEC"1"
BOM_COST"SM_THERM"
SEC_TYPE"0402"
SEC"1"
ROOM"CPU_FANS"
CDS_LOCATION"R9T5"
CDS_LIB"mstr_discrete"
LOCATION"R9T5"
VALUE"4.75K"
TOLERANCE"1%"
MATERIAL"CHIP"
WATTAGE"1/16W"
PACK_TYPE"0402"
PART_NUMBER"G21796-072";
"A"
$PN"1"14;
"B"
$PN"2"37;
%"P3V3_STBY"
"1","(-3225,3100)","0","mstr_symbols","I136";
;
SIZE"1B"
CDS_LIB"mstr_symbols"
VOLTAGE"3.3V"
BODY_TYPE"PLUMBING"
HDL_POWER"P3V3_STBY";
"G\NAC"14;
%"CAP_A"
"1","(-3300,2625)","2","dev_discrete","I137";
;
CDS_LOCATION"C9T1"
CDS_LIB"dev_discrete"
BOM_COST"SM_THERM"
CDS_SEC"1"
SEC_TYPE"0402V"
SEC"1"
ROOM"CPU_FANS"
LOCATION"C9T1"
VALUE"0.01UF"
TOLERANCE"10%"
VOLTAGE"25V"
MATERIAL"X7R"
PACK_TYPE"0402V"
PART_NUMBER"A36096-045";
"B"
$PN"2"13;
"A"
$PN"1"37;
%"CAP_A"
"1","(-1000,2275)","0","dev_discrete","I26";
;
CDS_LOCATION"C9M5"
BOM_COST"SM_THERM"
CDS_SEC"1"
SEC_TYPE"0402V"
SEC"1"
ROOM"CPU_FANS"
CDS_LIB"dev_discrete"
PART_NUMBER"A36096-030"
VALUE"0.1UF"
LOCATION"C9M5"
MATERIAL"X7R"
VOLTAGE"16V"
TOLERANCE"10%"
PACK_TYPE"0402V";
"B"
$PN"2"15;
"A"
$PN"1"3;
%"CAP"
"1","(-1300,2275)","0","mstr_discrete","I27";
;
CDS_SEC"1"
ROOM"CPU_FANS"
BOM_COST"SM_THERM"
SEC_TYPE"0805"
SEC"1"
CDS_LOCATION"C9M4"
MATERIAL"X6S"
CDS_LIB"mstr_discrete"
PART_NUMBER"C95333-007"
TOLERANCE"10%"
PACK_TYPE"0805"
VALUE"10UF"
LOCATION"C9M4"
VOLTAGE"16V";
"A"
$PN"1"3;
"B"
$PN"2"15;
%"CAP"
"1","(-1400,4350)","0","mstr_discrete","I3";
;
CDS_SEC"1"
SEC_TYPE"0805"
BOM_COST"SM_THERM"
SEC"1"
CDS_LOCATION"C1E21"
ROOM"CPU_FANS"
CDS_LIB"mstr_discrete"
MATERIAL"X6S"
LOCATION"C1E21"
PART_NUMBER"C95333-007"
VALUE"10UF"
TOLERANCE"10%"
PACK_TYPE"0805"
VOLTAGE"16V";
"A"
$PN"1"4;
"B"
$PN"2"11;
%"GND"
"1","(-1300,1950)","0","mstr_symbols","I30";
;
HDL_POWER"GND"
SIZE"1B"
VOLTAGE"0.0V"
CDS_LIB"mstr_symbols"
BODY_TYPE"PLUMBING";
"A\NAC"15;
%"CONN6_C74770005"
"1","(-775,1700)","0","mstr_conn","I32";
;
CDS_SEC"1"
SEC"1"
SEC_TYPE"PIP"
PACK_TYPE"PIP"
BOM_COST"SM_THERM"
ROOM"CPU_FANS"
CDS_LOCATION"J1B2"
CDS_LIB"mstr_conn"
LOCATION"J1B2"
MATERIAL"HDR"
PART_NUMBER"C74770-005";
"IO6"
$PN"6"31;
"IO5"
$PN"5"29;
"IO4"
$PN"4"28;
"IO3"
$PN"3"30;
"IO2"
$PN"2"3;
"IO1"
$PN"1"5;
%"CAP_A"
"1","(-1125,4325)","0","dev_discrete","I4";
;
CDS_SEC"1"
BOM_COST"SM_THERM"
SEC"1"
CDS_LOCATION"C1E20"
ROOM"CPU_FANS"
SEC_TYPE"0402V"
CDS_LIB"dev_discrete"
LOCATION"C1E20"
PART_NUMBER"A36096-030"
VALUE"0.1UF"
TOLERANCE"10%"
PACK_TYPE"0402V"
VOLTAGE"16V"
MATERIAL"X7R";
"B"
$PN"2"11;
"A"
$PN"1"4;
%"DIODE"
"1","(-1675,3825)","0","mstr_discrete","I42";
;
CDS_SEC"1"
BOM_COST"SM_THERM"
SEC_TYPE"SM"
SEC"1"
ROOM"CPU_FANS"
CDS_LOCATION"CR1F1"
CDS_LIB"mstr_discrete"
PART_NUMBER"H71799-001"
VALUE"SDMK0340L"
LOCATION"CR1F1"
PACK_TYPE"SM"
MATERIAL"IC";
"C"
$PN"1"26;
"A"
$PN"2"32;
%"RES"
"1","(-2525,3825)","0","mstr_discrete","I43";
;
CDS_SEC"1"
BOM_COST"SM_THERM"
CDS_LIB"mstr_discrete"
ROOM"CPU_FANS"
NO_XNET_CONNECTION"1"
CDS_LOCATION"R1F2"
SEC"1"
SEC_TYPE"0402"
MATERIAL"CHIP"
PACK_TYPE"0402"
TOLERANCE"1%"
LOCATION"R1F2"
PART_NUMBER"G21796-017"
VALUE"100.0"
WATTAGE"1/16W";
"B"
$PN"2"32;
"A"
$PN"1"35;
%"RES"
"2","(-2900,4025)","0","mstr_discrete","I45";
;
CDS_SEC"1"
BOM_COST"SM_THERM"
SEC_TYPE"0402"
SEC"1"
ROOM"CPU_FANS"
CDS_LOCATION"R1F1"
CDS_LIB"mstr_discrete"
LOCATION"R1F1"
VALUE"4.75K"
PART_NUMBER"G21796-072"
TOLERANCE"1%"
PACK_TYPE"0402"
MATERIAL"CHIP"
WATTAGE"1/16W";
"A"
$PN"1"17;
"B"
$PN"2"35;
%"CAP_A"
"1","(-2775,3625)","2","dev_discrete","I46";
;
CDS_LIB"dev_discrete"
ROOM"CPU_FANS"
SEC"1"
SEC_TYPE"0402V"
BOM_COST"SM_THERM"
CDS_LOCATION"C1F9"
CDS_SEC"1"
LOCATION"C1F9"
VALUE"0.01UF"
VOLTAGE"25V"
TOLERANCE"10%"
PACK_TYPE"0402V"
MATERIAL"X7R"
PART_NUMBER"A36096-045";
"B"
$PN"2"16;
"A"
$PN"1"35;
%"GND"
"1","(-2775,3375)","0","mstr_symbols","I47";
;
CDS_LIB"mstr_symbols"
HDL_POWER"GND"
SIZE"1B"
BODY_TYPE"PLUMBING"
VOLTAGE"0.0V";
"A\NAC"16;
%"P3V3_STBY"
"1","(-2900,4250)","0","mstr_symbols","I48";
;
SIZE"1B"
CDS_LIB"mstr_symbols"
VOLTAGE"3.3V"
BODY_TYPE"PLUMBING"
HDL_POWER"P3V3_STBY";
"G\NAC"17;
%"DIODE"
"4","(-1950,3325)","0","mstr_discrete","I50";
;
CDS_SEC"1"
BOM_COST"SM_THERM"
SEC_TYPE"SM"
SEC"1"
CDS_LOCATION"CR1E1"
ROOM"CPU_FANS"
CDS_LIB"mstr_discrete"
MATERIAL"EMPTY"
LOCATION"CR1E1"
PART_NUMBER"H71799-001"
VALUE"SDMK0340L"
PACK_TYPE"SM";
"A"
$PN"2"24;
"C"
$PN"1"18;
%"RES"
"2","(-2175,3400)","2","mstr_discrete","I51";
;
CDS_SEC"1"
ROOM"CPU_FANS"
SEC"1"
BOM_COST"SM_THERM"
SEC_TYPE"0402"
CDS_LIB"mstr_discrete"
CDS_LOCATION"R1E12"
TOLERANCE"1%"
LOCATION"R1E12"
PART_NUMBER"G21796-072"
VALUE"4.75K"
PACK_TYPE"0402"
MATERIAL"CHIP"
WATTAGE"1/16W";
"A"
$PN"1"18;
"B"
$PN"2"24;
%"P5V_STBY"
"1","(-1950,3625)","0","mstr_symbols","I52";
;
CDS_LIB"mstr_symbols"
SIZE"1B"
VOLTAGE"5.0V"
BODY_TYPE"PLUMBING"
HDL_POWER"P5V_STBY";
"G\NAC"18;
%"P3V3_STBY"
"1","(-3050,2175)","0","mstr_symbols","I61";
;
SIZE"1B"
CDS_LIB"mstr_symbols"
VOLTAGE"3.3V"
BODY_TYPE"PLUMBING"
HDL_POWER"P3V3_STBY";
"G\NAC"19;
%"DIODE"
"1","(-1825,1750)","0","mstr_discrete","I62";
;
CDS_SEC"1"
BOM_COST"SM_THERM"
SEC_TYPE"SM"
SEC"1"
ROOM"CPU_FANS"
CDS_LOCATION"CR1B2"
CDS_LIB"mstr_discrete"
LOCATION"CR1B2"
PART_NUMBER"H71799-001"
VALUE"SDMK0340L"
MATERIAL"IC"
PACK_TYPE"SM";
"C"
$PN"1"30;
"A"
$PN"2"34;
%"P5V_STBY"
"1","(-2100,1550)","0","mstr_symbols","I63";
;
SIZE"1B"
CDS_LIB"mstr_symbols"
VOLTAGE"5.0V"
BODY_TYPE"PLUMBING"
HDL_POWER"P5V_STBY";
"G\NAC"20;
%"DIODE"
"4","(-2100,1250)","0","mstr_discrete","I64";
;
CDS_SEC"1"
BOM_COST"SM_THERM"
SEC_TYPE"SM"
SEC"1"
CDS_LOCATION"CR1B1"
ROOM"CPU_FANS"
CDS_LIB"mstr_discrete"
PART_NUMBER"H71799-001"
VALUE"SDMK0340L"
LOCATION"CR1B1"
MATERIAL"EMPTY"
PACK_TYPE"SM";
"A"
$PN"2"28;
"C"
$PN"1"20;
%"RES"
"2","(-2325,1300)","2","mstr_discrete","I65";
;
CDS_SEC"1"
BOM_COST"SM_THERM"
SEC_TYPE"0402"
SEC"1"
ROOM"CPU_FANS"
CDS_LOCATION"R7F33"
CDS_LIB"mstr_discrete"
TOLERANCE"1%"
LOCATION"R7F33"
VALUE"4.75K"
WATTAGE"1/16W"
PACK_TYPE"0402"
MATERIAL"CHIP"
PART_NUMBER"G21796-072";
"A"
$PN"1"20;
"B"
$PN"2"28;
%"RES"
"1","(-2675,1750)","0","mstr_discrete","I67";
;
CDS_SEC"1"
BOM_COST"SM_THERM"
CDS_LOCATION"R1B22"
SEC"1"
SEC_TYPE"0402"
NO_XNET_CONNECTION"1"
ROOM"CPU_FANS"
CDS_LIB"mstr_discrete"
PART_NUMBER"G21796-017"
PACK_TYPE"0402"
MATERIAL"CHIP"
LOCATION"R1B22"
TOLERANCE"1%"
VALUE"100.0"
WATTAGE"1/16W";
"B"
$PN"2"34;
"A"
$PN"1"38;
%"CAP_A"
"1","(-2925,1550)","2","dev_discrete","I68";
;
CDS_LOCATION"C1B15"
SEC_TYPE"0402V"
CDS_LIB"dev_discrete"
ROOM"CPU_FANS"
SEC"1"
CDS_SEC"1"
BOM_COST"SM_THERM"
LOCATION"C1B15"
VOLTAGE"25V"
MATERIAL"X7R"
TOLERANCE"10%"
PART_NUMBER"A36096-045"
VALUE"0.01UF"
PACK_TYPE"0402V";
"B"
$PN"2"21;
"A"
$PN"1"38;
%"GND"
"1","(-2925,1300)","0","mstr_symbols","I69";
;
HDL_POWER"GND"
CDS_LIB"mstr_symbols"
SIZE"1B"
VOLTAGE"0.0V"
BODY_TYPE"PLUMBING";
"A\NAC"21;
%"RES"
"2","(-3050,1950)","0","mstr_discrete","I70";
;
CDS_SEC"1"
BOM_COST"SM_THERM"
SEC_TYPE"0402"
SEC"1"
ROOM"CPU_FANS"
CDS_LOCATION"R1B21"
CDS_LIB"mstr_discrete"
LOCATION"R1B21"
VALUE"4.75K"
PART_NUMBER"G21796-072"
WATTAGE"1/16W"
MATERIAL"CHIP"
TOLERANCE"1%"
PACK_TYPE"0402";
"A"
$PN"1"19;
"B"
$PN"2"38;
%"TTL1G07_A"
"1","(-6350,3850)","0","mstr_ttl","I88";
;
CDS_SEC"1"
PACK_TYPE"SOP"
BOM_COST"SM_THERM"
SEC_TYPE"SOP"
SEC"1"
ROOM"CPU_FANS"
CDS_LIB"mstr_ttl"
CDS_LOCATION"U8G2"
POWER_GROUP"VCC=P3V3_STBY;GND=GND"
PART_NUMBER"C88419-001"
MATERIAL"IC"
LOCATION"U8G2"
VALUE"74LVC1G07";
"Y"
$PN"4"44;
"A"
$PN"2"47;
%"CAP_A"
"1","(-6300,4450)","0","dev_discrete","I90";
;
ROOM"CPU_FANS"
BOM_COST"SM_THERM"
SEC_TYPE"0402V"
SEC"1"
CDS_SEC"1"
CDS_LOCATION"C2U27"
CDS_LIB"dev_discrete"
LOCATION"C2U27"
PART_NUMBER"A36096-030"
VALUE"0.1UF"
PACK_TYPE"0402V"
TOLERANCE"10%"
VOLTAGE"16V"
MATERIAL"X7R";
"B"
$PN"2"23;
"A"
$PN"1"22;
%"TTL1G07_A"
"1","(-6425,1100)","0","mstr_ttl","I92";
;
CDS_SEC"1"
BOM_COST"SM_THERM"
ROOM"CPU_FANS"
CDS_LOCATION"U8G3"
SEC"1"
SEC_TYPE"SOP"
CDS_LIB"mstr_ttl"
PACK_TYPE"SOP"
PART_NUMBER"C88419-001"
MATERIAL"IC"
VALUE"74LVC1G07"
LOCATION"U8G3"
POWER_GROUP"VCC=P3V3_STBY;GND=GND";
"Y"
$PN"4"43;
"A"
$PN"2"48;
%"CAP_A"
"1","(-6200,675)","0","dev_discrete","I93";
;
BOM_COST"SM_THERM"
ROOM"CPU_FANS"
SEC_TYPE"0402V"
SEC"1"
CDS_SEC"1"
CDS_LOCATION"C2U28"
CDS_LIB"dev_discrete"
LOCATION"C2U28"
PART_NUMBER"A36096-030"
VALUE"0.1UF"
TOLERANCE"10%"
PACK_TYPE"0402V"
VOLTAGE"16V"
MATERIAL"X7R";
"B"
$PN"2"1;
"A"
$PN"1"2;
%"P3V3_STBY"
"1","(-6300,4650)","0","mstr_symbols","I96";
;
CDS_LIB"mstr_symbols"
SIZE"1B"
VOLTAGE"3.3V"
BODY_TYPE"PLUMBING"
HDL_POWER"P3V3_STBY";
"G\NAC"22;
%"GND"
"1","(-6300,4250)","0","mstr_symbols","I97";
;
HDL_POWER"GND"
SIZE"1B"
BODY_TYPE"PLUMBING"
CDS_LIB"mstr_symbols"
VOLTAGE"0.0V";
"A\NAC"23;
%"RES"
"1","(-5450,3850)","0","mstr_discrete","I99";
;
CDS_SEC"1"
BOM_COST"SM_THERM"
ROOM"CPU_FANS"
SEC_TYPE"0402"
CDS_LIB"mstr_discrete"
SEC"1"
CDS_LOCATION"R2U42"
PACK_TYPE"0402"
TOLERANCE"1.0%"
PART_NUMBER"G21796-271"
LOCATION"R2U42"
MATERIAL"CHIP"
WATTAGE"1/16W"
VALUE"221";
"B"
$PN"2"40;
"A"
$PN"1"44;
END.
